FILE_TYPE = MULTI_PHYS_TABLE;
PART 'ZENER'
{======================================================================================================================================================================}
:VALUE  | PACK_TYPE | MATERIAL | PART_NUMBER     = EnvComp                  | PART_NUMBER  | JEDEC_TYPE | CLASS | DESCRIPTION                               | HEIGHT    | COMPONENT_TYPE | LEAD_LENGTH | LPID   | SPEED_URL | Status |RPL| AML | Bus_Unit | Days ;
{======================================================================================================================================================================}
'13V'   | 'SM'      | 'IC'     | 'H69095-001'(!) = ''                       | 'H69095-001' | 'SCR3125A' | 'IC'  | 'IC,DS,DIO,SMC,SMCJ13A,ZENER'             | '0.103 IN' | 'SMTOTHER'     | ''         | '472' | 'http://speed.intel.com:8081/speed/module/pdm/item/pdm_item_detail_direct.asp?item_cde=H69095-001&item_rev=01&url_param=unused' | '' | '' | '' | '' | '' 
'13V'   | 'SM'      | 'EMPTY'  | 'H69095-001'(!) = ''                       | 'H69095-001' | 'SCR3125A' | 'IO'  | 'IC,DS,DIO,SMC,SMCJ13A,ZENER'             | '0.103 IN' | 'SMTOTHER'     | ''         | '472' | 'http://speed.intel.com:8081/speed/module/pdm/item/pdm_item_detail_direct.asp?item_cde=H69095-001&item_rev=01&url_param=unused' | '' | '' | '' | '' | '' 
END_PART
END.
